#ISCELL
  mstr_misc dns *
  *
#ISCELL
  pure_quanta quanta_title_block_c *
  *
#ISCELL
  logical_power universal_gnd *
  page261_i1
#ISCELL
  logical_power universal_gnd *
  page261_i10
#CELL
  pure_quanta q_cap *
  page261_i11
#CELL
  pure_quanta isl99390frztr5935 *
  page261_i12
#CELL
  pure_quanta q_cap *
  page261_i13
#CELL
  pure_quanta q_res *
  page261_i14
#ISCELL
  logical_power universal_gnd *
  page261_i15
#CELL
  pure_quanta q_cap *
  page261_i16
#ISCELL
  logical_power vcc15 *
  page261_i17
#ISCELL
  standard offpage *
  page261_i18
#ISCELL
  standard offpage *
  page261_i19
#CELL
  pure_quanta q_res *
  page261_i2
#ISCELL
  logical_power universal_gnd *
  page261_i20
#ISCELL
  standard offpage *
  page261_i21
#ISCELL
  standard offpage *
  page261_i22
#ISCELL
  logical_power universal_gnd *
  page261_i23
#CELL
  pure_quanta q_cap *
  page261_i24
#CELL
  pure_quanta q_cap *
  page261_i25
#CELL
  pure_quanta q_res *
  page261_i26
#ISCELL
  logical_power vcc15 *
  page261_i27
#ISCELL
  logical_power universal_gnd *
  page261_i28
#CELL
  pure_quanta q_cap *
  page261_i29
#ISCELL
  logical_power universal_gnd *
  page261_i3
#ISCELL
  logical_power universal_gnd *
  page261_i30
#CELL
  pure_quanta q_res *
  page261_i31
#CELL
  pure_quanta q_cap *
  page261_i32
#ISCELL
  logical_power universal_gnd *
  page261_i33
#CELL
  pure_quanta q_res *
  page261_i34
#CELL
  pure_quanta q_cap *
  page261_i35
#CELL
  pure_quanta q_cap *
  page261_i36
#CELL
  pure_quanta q_cap *
  page261_i37
#CELL
  pure_quanta q_cap *
  page261_i38
#CELL
  pure_quanta q_inductor *
  page261_i39
#ISCELL
  logical_power universal_gnd *
  page261_i4
#CELL
  pure_quanta q_cap *
  page261_i40
#CELL
  pure_quanta q_cap *
  page261_i41
#ISCELL
  logical_power universal_gnd *
  page261_i42
#ISCELL
  logical_power vcc15 *
  page261_i43
#ISCELL
  logical_power universal_gnd *
  page261_i44
#CELL
  pure_quanta q_cap *
  page261_i45
#CELL
  pure_quanta q_res *
  page261_i46
#CELL
  pure_quanta q_res *
  page261_i47
#CELL
  pure_quanta q_cap *
  page261_i48
#CELL
  pure_quanta q_cap *
  page261_i49
#CELL
  pure_quanta q_res *
  page261_i5
#CELL
  pure_quanta q_cap *
  page261_i50
#CELL
  pure_quanta q_cap *
  page261_i51
#CELL
  pure_quanta q_inductor *
  page261_i52
#ISCELL
  logical_power universal_gnd *
  page261_i53
#CELL
  pure_quanta q_cap *
  page261_i54
#ISCELL
  logical_power vcc15 *
  page261_i55
#CELL
  pure_quanta q_cap *
  page261_i56
#CELL
  pure_quanta q_cap *
  page261_i57
#ISCELL
  logical_power vcc15 *
  page261_i58
#ISCELL
  logical_power gnd *
  page261_i59
#ISCELL
  standard offpage *
  page261_i6
#CELL
  pure_quanta q_cap *
  page261_i60
#ISCELL
  logical_power vcc15 *
  page261_i61
#CELL
  pure_quanta q_inductor *
  page261_i62
#CELL
  pure_quanta q_res *
  page261_i63
#ISCELL
  logical_power universal_gnd *
  page261_i64
#ISCELL
  logical_power vcc15 *
  page261_i65
#CELL
  pure_quanta q_capp *
  page261_i66
#CELL
  pure_quanta q_capp *
  page261_i67
#CELL
  pure_quanta q_capp *
  page261_i68
#CELL
  pure_quanta q_capp *
  page261_i69
#ISCELL
  standard offpage *
  page261_i7
#CELL
  pure_quanta q_capp *
  page261_i70
#ISCELL
  logical_power universal_gnd *
  page261_i71
#ISCELL
  logical_power vcc15 *
  page261_i72
#ISCELL
  logical_power universal_gnd *
  page261_i73
#CELL
  pure_quanta q_capp *
  page261_i74
#CELL
  pure_quanta q_capp *
  page261_i75
#ISCELL
  logical_power universal_gnd *
  page261_i76
#ISCELL
  logical_power vcc15 *
  page261_i77
#ISCELL
  logical_power vcc15 *
  page261_i78
#CELL
  pure_quanta isl99390frztr5935 *
  page261_i79
#ISCELL
  standard offpage *
  page261_i8
#ISCELL
  standard offpage *
  page261_i9
